# T6G (Grand Teton) — schematic netlist excerpt (pin names and nets, part order shuffled) for the footprints in the layout excerpt that follows; sources: Cadence DE-HDL packaged netlist, KiCad conversion of 04192023_DAF0TMB3IC0_F0TG_MB_C_brd_V02_OCP.brd

R2968  Q_RES  0 5% CHIP  pkg 0402LF  page 250 : A = SMB_PCIE0_3V3AUX_SDA_R3 ; B = SMB_SENSOR_M2_P1_3V3AUX_SDA
R8093  Q_RES  100K 1% CHIP  pkg 0402LF  page 136 : A = OCP_V3_1_P3V3_R1_PWRGD ; B = GND

(kicad_pcb
	(version 20260206)
	(generator "pcbnew")
	(generator_version "10.0")
	(general
		(thickness 1.6)
		(legacy_teardrops no)
	)
	(paper "A4")
	(title_block
		(title "04192023_DAF0TMB3IC0_F0TG_MB_C_brd_V02_OCP.brd")
		(comment 1 "Grand Teton / footprints 1079-1080 of 8354")
	)
	(layers
		(0 "F.Cu" signal "TOP")
		(4 "In1.Cu" signal "GND")
		(6 "In2.Cu" signal "IN1")
		(8 "In3.Cu" signal "GND1")
		(10 "In4.Cu" signal "IN2")
		(12 "In5.Cu" signal "GND2")
		(14 "In6.Cu" signal "IN3")
		(16 "In7.Cu" signal "GND3")
		(18 "In8.Cu" signal "VCC")
		(20 "In9.Cu" signal "VCC1")
		(22 "In10.Cu" signal "GND4")
		(24 "In11.Cu" signal "IN4")
		(26 "In12.Cu" signal "GND5")
		(28 "In13.Cu" signal "IN5")
		(30 "In14.Cu" signal "GND6")
		(32 "In15.Cu" signal "IN6")
		(34 "In16.Cu" signal "GND7")
		(2 "B.Cu" signal "BOTTOM")
		(9 "F.Adhes" user "F.Adhesive")
		(11 "B.Adhes" user "B.Adhesive")
		(13 "F.Paste" user "Package Geometry/Pastemask Top")
		(15 "B.Paste" user "Package Geometry/Pastemask Bottom")
		(5 "F.SilkS" user "Ref Des/Silkscreen Top")
		(7 "B.SilkS" user "Ref Des/Silkscreen Bottom")
		(1 "F.Mask" user "Board Geometry/Soldermask Top")
		(3 "B.Mask" user "Board Geometry/Soldermask Bottom")
		(17 "Dwgs.User" user "User.Drawings")
		(19 "Cmts.User" user "User.Comments")
		(21 "Eco1.User" user "User.Eco1")
		(23 "Eco2.User" user "User.Eco2")
		(25 "Edge.Cuts" user "Board Geometry/Outline")
		(27 "Margin" user)
		(31 "F.CrtYd" user "Package Geometry/Place Bound Top")
		(29 "B.CrtYd" user "Package Geometry/Place Bound Bottom")
		(35 "F.Fab" user "Ref Des/Assembly Top")
		(33 "B.Fab" user "Ref Des/Assembly Bottom")
	)
	(footprint ""
		(layer "F.Cu")
		(at 279.513792 -116.67617 180)
		(property "Reference" "R2968"
			(at 0 0 180)
			(layer "F.SilkS")
			(hide yes)
			(effects
				(font
					(size 1.27 1.27)
				)
			)
		)
		(property "Value" ""
			(at 0 0 180)
			(layer "F.Fab")
			(effects
				(font
					(size 1.27 1.27)
				)
			)
		)
		(duplicate_pad_numbers_are_jumpers no)
		(fp_line
			(start 0.7874 0.4064)
			(end -0.7874 0.4064)
			(stroke
				(width 0.1524)
				(type default)
			)
			(layer "F.SilkS")
		)
		(fp_line
			(start 0.7874 -0.4064)
			(end 0.7874 0.4064)
			(stroke
				(width 0.1524)
				(type default)
			)
			(layer "F.SilkS")
		)
		(fp_line
			(start -0.7874 0.4064)
			(end -0.7874 -0.4064)
			(stroke
				(width 0.1524)
				(type default)
			)
			(layer "F.SilkS")
		)
		(fp_line
			(start -0.7874 -0.4064)
			(end 0.7874 -0.4064)
			(stroke
				(width 0.1524)
				(type default)
			)
			(layer "F.SilkS")
		)
		(fp_line
			(start 0.67945 0.3048)
			(end 0.120396 0.3048)
			(stroke
				(width 0.1)
				(type default)
			)
			(layer "F.Fab")
		)
		(fp_line
			(start 0.67945 -0.3048)
			(end 0.67945 0.3048)
			(stroke
				(width 0.1)
				(type default)
			)
			(layer "F.Fab")
		)
		(fp_line
			(start 0.12065 -0.2794)
			(end 0.12065 -0.3048)
			(stroke
				(width 0.1)
				(type default)
			)
			(layer "F.Fab")
		)
		(fp_line
			(start 0.12065 -0.3048)
			(end 0.67945 -0.3048)
			(stroke
				(width 0.1)
				(type default)
			)
			(layer "F.Fab")
		)
		(fp_line
			(start 0.120396 0.3048)
			(end 0.120396 0.2794)
			(stroke
				(width 0.1)
				(type default)
			)
			(layer "F.Fab")
		)
		(fp_line
			(start 0.120396 0.2794)
			(end -0.12065 0.2794)
			(stroke
				(width 0.1)
				(type default)
			)
			(layer "F.Fab")
		)
		(fp_line
			(start -0.12065 0.3048)
			(end -0.67945 0.3048)
			(stroke
				(width 0.1)
				(type default)
			)
			(layer "F.Fab")
		)
		(fp_line
			(start -0.12065 0.2794)
			(end -0.12065 0.3048)
			(stroke
				(width 0.1)
				(type default)
			)
			(layer "F.Fab")
		)
		(fp_line
			(start -0.12065 -0.2794)
			(end 0.12065 -0.2794)
			(stroke
				(width 0.1)
				(type default)
			)
			(layer "F.Fab")
		)
		(fp_line
			(start -0.12065 -0.305054)
			(end -0.12065 -0.2794)
			(stroke
				(width 0.1)
				(type default)
			)
			(layer "F.Fab")
		)
		(fp_line
			(start -0.67945 0.3048)
			(end -0.67945 -0.305054)
			(stroke
				(width 0.1)
				(type default)
			)
			(layer "F.Fab")
		)
		(fp_line
			(start -0.67945 -0.305054)
			(end -0.12065 -0.305054)
			(stroke
				(width 0.1)
				(type default)
			)
			(layer "F.Fab")
		)
		(pad "1" smd circle
			(at -0.40005 0 180)
			(size 0 0)
			(layers "F.Cu" "F.Mask" "F.Paste")
			(net "SMB_PCIE0_3V3AUX_SDA_R3")
		)
		(pad "2" smd circle
			(at 0.40005 0 180)
			(size 0 0)
			(layers "F.Cu" "F.Mask" "F.Paste")
			(net "SMB_SENSOR_M2_P1_3V3AUX_SDA")
		)
	)
	(footprint ""
		(layer "F.Cu")
		(at 413.766 -100.203 90)
		(property "Reference" "R8093"
			(at 0 0 90)
			(layer "F.SilkS")
			(hide yes)
			(effects
				(font
					(size 1.27 1.27)
				)
			)
		)
		(property "Value" ""
			(at 0 0 90)
			(layer "F.Fab")
			(effects
				(font
					(size 1.27 1.27)
				)
			)
		)
		(duplicate_pad_numbers_are_jumpers no)
		(fp_line
			(start 0.7874 -0.4064)
			(end 0.7874 0.4064)
			(stroke
				(width 0.1524)
				(type default)
			)
			(layer "F.SilkS")
		)
		(fp_line
			(start -0.7874 -0.4064)
			(end 0.7874 -0.4064)
			(stroke
				(width 0.1524)
				(type default)
			)
			(layer "F.SilkS")
		)
		(fp_line
			(start 0.7874 0.4064)
			(end -0.7874 0.4064)
			(stroke
				(width 0.1524)
				(type default)
			)
			(layer "F.SilkS")
		)
		(fp_line
			(start -0.7874 0.4064)
			(end -0.7874 -0.4064)
			(stroke
				(width 0.1524)
				(type default)
			)
			(layer "F.SilkS")
		)
		(fp_line
			(start -0.12065 -0.305054)
			(end -0.12065 -0.2794)
			(stroke
				(width 0.1)
				(type default)
			)
			(layer "F.Fab")
		)
		(fp_line
			(start -0.67945 -0.305054)
			(end -0.12065 -0.305054)
			(stroke
				(width 0.1)
				(type default)
			)
			(layer "F.Fab")
		)
		(fp_line
			(start 0.67945 -0.3048)
			(end 0.67945 0.3048)
			(stroke
				(width 0.1)
				(type default)
			)
			(layer "F.Fab")
		)
		(fp_line
			(start 0.12065 -0.3048)
			(end 0.67945 -0.3048)
			(stroke
				(width 0.1)
				(type default)
			)
			(layer "F.Fab")
		)
		(fp_line
			(start 0.12065 -0.2794)
			(end 0.12065 -0.3048)
			(stroke
				(width 0.1)
				(type default)
			)
			(layer "F.Fab")
		)
		(fp_line
			(start -0.12065 -0.2794)
			(end 0.12065 -0.2794)
			(stroke
				(width 0.1)
				(type default)
			)
			(layer "F.Fab")
		)
		(fp_line
			(start 0.120396 0.2794)
			(end -0.12065 0.2794)
			(stroke
				(width 0.1)
				(type default)
			)
			(layer "F.Fab")
		)
		(fp_line
			(start -0.12065 0.2794)
			(end -0.12065 0.3048)
			(stroke
				(width 0.1)
				(type default)
			)
			(layer "F.Fab")
		)
		(fp_line
			(start 0.67945 0.3048)
			(end 0.120396 0.3048)
			(stroke
				(width 0.1)
				(type default)
			)
			(layer "F.Fab")
		)
		(fp_line
			(start 0.120396 0.3048)
			(end 0.120396 0.2794)
			(stroke
				(width 0.1)
				(type default)
			)
			(layer "F.Fab")
		)
		(fp_line
			(start -0.12065 0.3048)
			(end -0.67945 0.3048)
			(stroke
				(width 0.1)
				(type default)
			)
			(layer "F.Fab")
		)
		(fp_line
			(start -0.67945 0.3048)
			(end -0.67945 -0.305054)
			(stroke
				(width 0.1)
				(type default)
			)
			(layer "F.Fab")
		)
		(pad "1" smd circle
			(at -0.40005 0 90)
			(size 0 0)
			(layers "F.Cu" "F.Mask" "F.Paste")
			(net "OCP_V3_1_P3V3_R1_PWRGD")
		)
		(pad "2" smd circle
			(at 0.40005 0 90)
			(size 0 0)
			(layers "F.Cu" "F.Mask" "F.Paste")
			(net "GND")
		)
	)
)
